# T6G (Grand Teton) — schematic netlist excerpt (pin names and nets, part order shuffled) for the footprints in the layout excerpt that follows; sources: Cadence DE-HDL packaged netlist, KiCad conversion of 04192023_DAF0TMB3IC0_F0TG_MB_C_brd_V02_OCP.brd

R1448  Q_RES  1K 1% CHIP  pkg 0201LF  page 185 : A = P1V8_CPU1_RT_1D ; B = SMB_RT_CPU1_P1_ROM_MUX_1D_SDA
R3724  Q_RES  2.2K 5% CHIP  pkg 0402LF  page 252 : A = P3V3_AUX ; B = SMB_VR_3V3AUX_SDA
R6284  Q_RES  10 1% CHIP  pkg 0402LF  page 179 : A = USB_HUB2_TI_FULLPWRMGMTZ_MRP_PROG_FUNC3 ; B = GND

(kicad_pcb
	(version 20260206)
	(generator "pcbnew")
	(generator_version "10.0")
	(general
		(thickness 1.6)
		(legacy_teardrops no)
	)
	(paper "A4")
	(title_block
		(title "04192023_DAF0TMB3IC0_F0TG_MB_C_brd_V02_OCP.brd")
		(comment 1 "Grand Teton / footprints 790-792 of 8354")
	)
	(layers
		(0 "F.Cu" signal "TOP")
		(4 "In1.Cu" signal "GND")
		(6 "In2.Cu" signal "IN1")
		(8 "In3.Cu" signal "GND1")
		(10 "In4.Cu" signal "IN2")
		(12 "In5.Cu" signal "GND2")
		(14 "In6.Cu" signal "IN3")
		(16 "In7.Cu" signal "GND3")
		(18 "In8.Cu" signal "VCC")
		(20 "In9.Cu" signal "VCC1")
		(22 "In10.Cu" signal "GND4")
		(24 "In11.Cu" signal "IN4")
		(26 "In12.Cu" signal "GND5")
		(28 "In13.Cu" signal "IN5")
		(30 "In14.Cu" signal "GND6")
		(32 "In15.Cu" signal "IN6")
		(34 "In16.Cu" signal "GND7")
		(2 "B.Cu" signal "BOTTOM")
		(9 "F.Adhes" user "F.Adhesive")
		(11 "B.Adhes" user "B.Adhesive")
		(13 "F.Paste" user "Package Geometry/Pastemask Top")
		(15 "B.Paste" user "Package Geometry/Pastemask Bottom")
		(5 "F.SilkS" user "Ref Des/Silkscreen Top")
		(7 "B.SilkS" user "Ref Des/Silkscreen Bottom")
		(1 "F.Mask" user "Board Geometry/Soldermask Top")
		(3 "B.Mask" user "Board Geometry/Soldermask Bottom")
		(17 "Dwgs.User" user "User.Drawings")
		(19 "Cmts.User" user "User.Comments")
		(21 "Eco1.User" user "User.Eco1")
		(23 "Eco2.User" user "User.Eco2")
		(25 "Edge.Cuts" user "Board Geometry/Outline")
		(27 "Margin" user)
		(31 "F.CrtYd" user "Package Geometry/Place Bound Top")
		(29 "B.CrtYd" user "Package Geometry/Place Bound Bottom")
		(35 "F.Fab" user "Ref Des/Assembly Top")
		(33 "B.Fab" user "Ref Des/Assembly Bottom")
	)
	(footprint ""
		(layer "F.Cu")
		(at 116.331238 -41.17975 90)
		(property "Reference" "R6284"
			(at 0 0 90)
			(layer "F.SilkS")
			(hide yes)
			(effects
				(font
					(size 1.27 1.27)
				)
			)
		)
		(property "Value" ""
			(at 0 0 90)
			(layer "F.Fab")
			(effects
				(font
					(size 1.27 1.27)
				)
			)
		)
		(duplicate_pad_numbers_are_jumpers no)
		(fp_line
			(start 0.7874 -0.4064)
			(end 0.7874 0.4064)
			(stroke
				(width 0.1524)
				(type default)
			)
			(layer "F.SilkS")
		)
		(fp_line
			(start -0.7874 -0.4064)
			(end 0.7874 -0.4064)
			(stroke
				(width 0.1524)
				(type default)
			)
			(layer "F.SilkS")
		)
		(fp_line
			(start 0.7874 0.4064)
			(end -0.7874 0.4064)
			(stroke
				(width 0.1524)
				(type default)
			)
			(layer "F.SilkS")
		)
		(fp_line
			(start -0.7874 0.4064)
			(end -0.7874 -0.4064)
			(stroke
				(width 0.1524)
				(type default)
			)
			(layer "F.SilkS")
		)
		(fp_line
			(start -0.12065 -0.305054)
			(end -0.12065 -0.2794)
			(stroke
				(width 0.1)
				(type default)
			)
			(layer "F.Fab")
		)
		(fp_line
			(start -0.67945 -0.305054)
			(end -0.12065 -0.305054)
			(stroke
				(width 0.1)
				(type default)
			)
			(layer "F.Fab")
		)
		(fp_line
			(start 0.67945 -0.3048)
			(end 0.67945 0.3048)
			(stroke
				(width 0.1)
				(type default)
			)
			(layer "F.Fab")
		)
		(fp_line
			(start 0.12065 -0.3048)
			(end 0.67945 -0.3048)
			(stroke
				(width 0.1)
				(type default)
			)
			(layer "F.Fab")
		)
		(fp_line
			(start 0.12065 -0.2794)
			(end 0.12065 -0.3048)
			(stroke
				(width 0.1)
				(type default)
			)
			(layer "F.Fab")
		)
		(fp_line
			(start -0.12065 -0.2794)
			(end 0.12065 -0.2794)
			(stroke
				(width 0.1)
				(type default)
			)
			(layer "F.Fab")
		)
		(fp_line
			(start 0.120396 0.2794)
			(end -0.12065 0.2794)
			(stroke
				(width 0.1)
				(type default)
			)
			(layer "F.Fab")
		)
		(fp_line
			(start -0.12065 0.2794)
			(end -0.12065 0.3048)
			(stroke
				(width 0.1)
				(type default)
			)
			(layer "F.Fab")
		)
		(fp_line
			(start 0.67945 0.3048)
			(end 0.120396 0.3048)
			(stroke
				(width 0.1)
				(type default)
			)
			(layer "F.Fab")
		)
		(fp_line
			(start 0.120396 0.3048)
			(end 0.120396 0.2794)
			(stroke
				(width 0.1)
				(type default)
			)
			(layer "F.Fab")
		)
		(fp_line
			(start -0.12065 0.3048)
			(end -0.67945 0.3048)
			(stroke
				(width 0.1)
				(type default)
			)
			(layer "F.Fab")
		)
		(fp_line
			(start -0.67945 0.3048)
			(end -0.67945 -0.305054)
			(stroke
				(width 0.1)
				(type default)
			)
			(layer "F.Fab")
		)
		(pad "1" smd circle
			(at -0.40005 0 90)
			(size 0 0)
			(layers "F.Cu" "F.Mask" "F.Paste")
			(net "USB_HUB2_TI_FULLPWRMGMTZ_MRP_PROG_FUNC3")
		)
		(pad "2" smd circle
			(at 0.40005 0 90)
			(size 0 0)
			(layers "F.Cu" "F.Mask" "F.Paste")
			(net "GND")
		)
	)
	(footprint ""
		(layer "F.Cu")
		(at 254.592836 -123.10745)
		(property "Reference" "R3724"
			(at 0 0 0)
			(layer "F.SilkS")
			(hide yes)
			(effects
				(font
					(size 1.27 1.27)
				)
			)
		)
		(property "Value" ""
			(at 0 0 0)
			(layer "F.Fab")
			(effects
				(font
					(size 1.27 1.27)
				)
			)
		)
		(duplicate_pad_numbers_are_jumpers no)
		(fp_line
			(start -0.7874 -0.4064)
			(end 0.7874 -0.4064)
			(stroke
				(width 0.1524)
				(type default)
			)
			(layer "F.SilkS")
		)
		(fp_line
			(start -0.7874 0.4064)
			(end -0.7874 -0.4064)
			(stroke
				(width 0.1524)
				(type default)
			)
			(layer "F.SilkS")
		)
		(fp_line
			(start 0.7874 -0.4064)
			(end 0.7874 0.4064)
			(stroke
				(width 0.1524)
				(type default)
			)
			(layer "F.SilkS")
		)
		(fp_line
			(start 0.7874 0.4064)
			(end -0.7874 0.4064)
			(stroke
				(width 0.1524)
				(type default)
			)
			(layer "F.SilkS")
		)
		(fp_line
			(start -0.67945 -0.305054)
			(end -0.12065 -0.305054)
			(stroke
				(width 0.1)
				(type default)
			)
			(layer "F.Fab")
		)
		(fp_line
			(start -0.67945 0.3048)
			(end -0.67945 -0.305054)
			(stroke
				(width 0.1)
				(type default)
			)
			(layer "F.Fab")
		)
		(fp_line
			(start -0.12065 -0.305054)
			(end -0.12065 -0.2794)
			(stroke
				(width 0.1)
				(type default)
			)
			(layer "F.Fab")
		)
		(fp_line
			(start -0.12065 -0.2794)
			(end 0.12065 -0.2794)
			(stroke
				(width 0.1)
				(type default)
			)
			(layer "F.Fab")
		)
		(fp_line
			(start -0.12065 0.2794)
			(end -0.12065 0.3048)
			(stroke
				(width 0.1)
				(type default)
			)
			(layer "F.Fab")
		)
		(fp_line
			(start -0.12065 0.3048)
			(end -0.67945 0.3048)
			(stroke
				(width 0.1)
				(type default)
			)
			(layer "F.Fab")
		)
		(fp_line
			(start 0.120396 0.2794)
			(end -0.12065 0.2794)
			(stroke
				(width 0.1)
				(type default)
			)
			(layer "F.Fab")
		)
		(fp_line
			(start 0.120396 0.3048)
			(end 0.120396 0.2794)
			(stroke
				(width 0.1)
				(type default)
			)
			(layer "F.Fab")
		)
		(fp_line
			(start 0.12065 -0.3048)
			(end 0.67945 -0.3048)
			(stroke
				(width 0.1)
				(type default)
			)
			(layer "F.Fab")
		)
		(fp_line
			(start 0.12065 -0.2794)
			(end 0.12065 -0.3048)
			(stroke
				(width 0.1)
				(type default)
			)
			(layer "F.Fab")
		)
		(fp_line
			(start 0.67945 -0.3048)
			(end 0.67945 0.3048)
			(stroke
				(width 0.1)
				(type default)
			)
			(layer "F.Fab")
		)
		(fp_line
			(start 0.67945 0.3048)
			(end 0.120396 0.3048)
			(stroke
				(width 0.1)
				(type default)
			)
			(layer "F.Fab")
		)
		(pad "1" smd circle
			(at -0.40005 0)
			(size 0 0)
			(layers "F.Cu" "F.Mask" "F.Paste")
			(net "P3V3_AUX")
		)
		(pad "2" smd circle
			(at 0.40005 0)
			(size 0 0)
			(layers "F.Cu" "F.Mask" "F.Paste")
			(net "SMB_VR_3V3AUX_SDA")
		)
	)
	(footprint ""
		(layer "F.Cu")
		(at 118.11 -401.1676)
		(property "Reference" "R1448"
			(at 0 0 0)
			(layer "F.SilkS")
			(hide yes)
			(effects
				(font
					(size 1.27 1.27)
				)
			)
		)
		(property "Value" ""
			(at 0 0 0)
			(layer "F.Fab")
			(effects
				(font
					(size 1.27 1.27)
				)
			)
		)
		(duplicate_pad_numbers_are_jumpers no)
		(fp_line
			(start -0.32512 -0.175006)
			(end 0.32512 -0.175006)
			(stroke
				(width 0.1)
				(type default)
			)
			(layer "F.Fab")
		)
		(fp_line
			(start -0.32512 0.175006)
			(end -0.32512 -0.175006)
			(stroke
				(width 0.1)
				(type default)
			)
			(layer "F.Fab")
		)
		(fp_line
			(start 0.32512 -0.175006)
			(end 0.32512 0.175006)
			(stroke
				(width 0.1)
				(type default)
			)
			(layer "F.Fab")
		)
		(fp_line
			(start 0.32512 0.175006)
			(end -0.32512 0.175006)
			(stroke
				(width 0.1)
				(type default)
			)
			(layer "F.Fab")
		)
		(pad "1" smd rect
			(at -0.2667 0)
			(size 0.3048 0.381)
			(layers "F.Cu" "F.Mask" "F.Paste")
			(net "P1V8_CPU1_RT_1D")
		)
		(pad "2" smd rect
			(at 0.2667 0 180)
			(size 0.3048 0.381)
			(layers "F.Cu" "F.Mask" "F.Paste")
			(net "SMB_RT_CPU1_P1_ROM_MUX_1D_SDA")
		)
	)
)
